(kicad_pcb
	(version 20260206)
	(generator "pcbnew")
	(generator_version "10.0")
	(general
		(thickness 1.6)
		(legacy_teardrops no)
	)
	(paper "A4")
	(title_block
		(title "9052_F0T_PDB_Converter_Brick_F_V03_1208_1600_OCP.brd")
		(comment 1 "Grand Teton / footprints 444-449 of 578")
	)
	(layers
		(0 "F.Cu" signal "TOP")
		(4 "In1.Cu" signal "GND")
		(6 "In2.Cu" signal "IN1")
		(8 "In3.Cu" signal "GND1")
		(10 "In4.Cu" signal "VCC")
		(12 "In5.Cu" signal "VCC1")
		(14 "In6.Cu" signal "GND2")
		(16 "In7.Cu" signal "IN2")
		(18 "In8.Cu" signal "GND3")
		(2 "B.Cu" signal "BOTTOM")
		(9 "F.Adhes" user "F.Adhesive")
		(11 "B.Adhes" user "B.Adhesive")
		(13 "F.Paste" user "Package Geometry/Pastemask Top")
		(15 "B.Paste" user "Package Geometry/Pastemask Bottom")
		(5 "F.SilkS" user "Ref Des/Silkscreen Top")
		(7 "B.SilkS" user "Ref Des/Silkscreen Bottom")
		(1 "F.Mask" user "Board Geometry/Soldermask Top")
		(3 "B.Mask" user "Board Geometry/Soldermask Bottom")
		(17 "Dwgs.User" user "User.Drawings")
		(19 "Cmts.User" user "User.Comments")
		(21 "Eco1.User" user "User.Eco1")
		(23 "Eco2.User" user "User.Eco2")
		(25 "Edge.Cuts" user "Board Geometry/Outline")
		(27 "Margin" user)
		(31 "F.CrtYd" user "Package Geometry/Place Bound Top")
		(29 "B.CrtYd" user "Package Geometry/Place Bound Bottom")
		(35 "F.Fab" user "Ref Des/Assembly Top")
		(33 "B.Fab" user "Ref Des/Assembly Bottom")
	)
	(footprint ""
		(layer "B.Cu")
		(at 38.989 -89.027)
		(property "Reference" "R77"
			(at 0 0 0)
			(layer "B.SilkS")
			(hide yes)
			(effects
				(font
					(size 1.27 1.27)
				)
				(justify mirror)
			)
		)
		(property "Value" ""
			(at 0 0 0)
			(layer "B.Fab")
			(effects
				(font
					(size 1.27 1.27)
				)
				(justify mirror)
			)
		)
		(duplicate_pad_numbers_are_jumpers no)
		(fp_line
			(start -0.7874 -0.4064)
			(end -0.7874 0.4064)
			(stroke
				(width 0.1524)
				(type default)
			)
			(layer "B.SilkS")
		)
		(fp_line
			(start -0.7874 0.4064)
			(end 0.7874 0.4064)
			(stroke
				(width 0.1524)
				(type default)
			)
			(layer "B.SilkS")
		)
		(fp_line
			(start 0.7874 -0.4064)
			(end -0.7874 -0.4064)
			(stroke
				(width 0.1524)
				(type default)
			)
			(layer "B.SilkS")
		)
		(fp_line
			(start 0.7874 0.4064)
			(end 0.7874 -0.4064)
			(stroke
				(width 0.1524)
				(type default)
			)
			(layer "B.SilkS")
		)
		(fp_line
			(start -0.67945 -0.3048)
			(end -0.67945 0.3048)
			(stroke
				(width 0.1)
				(type default)
			)
			(layer "B.Fab")
		)
		(fp_line
			(start -0.67945 0.3048)
			(end -0.120396 0.3048)
			(stroke
				(width 0.1)
				(type default)
			)
			(layer "B.Fab")
		)
		(fp_line
			(start -0.12065 -0.3048)
			(end -0.67945 -0.3048)
			(stroke
				(width 0.1)
				(type default)
			)
			(layer "B.Fab")
		)
		(fp_line
			(start -0.12065 -0.2794)
			(end -0.12065 -0.3048)
			(stroke
				(width 0.1)
				(type default)
			)
			(layer "B.Fab")
		)
		(fp_line
			(start -0.120396 0.2794)
			(end 0.12065 0.2794)
			(stroke
				(width 0.1)
				(type default)
			)
			(layer "B.Fab")
		)
		(fp_line
			(start -0.120396 0.3048)
			(end -0.120396 0.2794)
			(stroke
				(width 0.1)
				(type default)
			)
			(layer "B.Fab")
		)
		(fp_line
			(start 0.12065 -0.305054)
			(end 0.12065 -0.2794)
			(stroke
				(width 0.1)
				(type default)
			)
			(layer "B.Fab")
		)
		(fp_line
			(start 0.12065 -0.2794)
			(end -0.12065 -0.2794)
			(stroke
				(width 0.1)
				(type default)
			)
			(layer "B.Fab")
		)
		(fp_line
			(start 0.12065 0.2794)
			(end 0.12065 0.3048)
			(stroke
				(width 0.1)
				(type default)
			)
			(layer "B.Fab")
		)
		(fp_line
			(start 0.12065 0.3048)
			(end 0.67945 0.3048)
			(stroke
				(width 0.1)
				(type default)
			)
			(layer "B.Fab")
		)
		(fp_line
			(start 0.67945 -0.305054)
			(end 0.12065 -0.305054)
			(stroke
				(width 0.1)
				(type default)
			)
			(layer "B.Fab")
		)
		(fp_line
			(start 0.67945 0.3048)
			(end 0.67945 -0.305054)
			(stroke
				(width 0.1)
				(type default)
			)
			(layer "B.Fab")
		)
		(pad "1" smd circle
			(at 0.40005 0 180)
			(size 0 0)
			(layers "B.Cu" "B.Mask" "B.Paste")
			(net "SMB_HPDB_MISC_SDA")
		)
		(pad "2" smd circle
			(at -0.40005 0 180)
			(size 0 0)
			(layers "B.Cu" "B.Mask" "B.Paste")
			(net "SMB_HPDB_MISC_R_SDA")
		)
	)
	(footprint ""
		(layer "B.Cu")
		(at 216.154 -69.723 -90)
		(property "Reference" "R134"
			(at 0 0 90)
			(layer "B.SilkS")
			(hide yes)
			(effects
				(font
					(size 1.27 1.27)
				)
				(justify mirror)
			)
		)
		(property "Value" ""
			(at 0 0 90)
			(layer "B.Fab")
			(effects
				(font
					(size 1.27 1.27)
				)
				(justify mirror)
			)
		)
		(duplicate_pad_numbers_are_jumpers no)
		(fp_line
			(start -0.7874 0.4064)
			(end 0.7874 0.4064)
			(stroke
				(width 0.1524)
				(type default)
			)
			(layer "B.SilkS")
		)
		(fp_line
			(start 0.7874 0.4064)
			(end 0.7874 -0.4064)
			(stroke
				(width 0.1524)
				(type default)
			)
			(layer "B.SilkS")
		)
		(fp_line
			(start -0.7874 -0.4064)
			(end -0.7874 0.4064)
			(stroke
				(width 0.1524)
				(type default)
			)
			(layer "B.SilkS")
		)
		(fp_line
			(start 0.7874 -0.4064)
			(end -0.7874 -0.4064)
			(stroke
				(width 0.1524)
				(type default)
			)
			(layer "B.SilkS")
		)
		(fp_line
			(start -0.67945 0.3048)
			(end -0.120396 0.3048)
			(stroke
				(width 0.1)
				(type default)
			)
			(layer "B.Fab")
		)
		(fp_line
			(start -0.120396 0.3048)
			(end -0.120396 0.2794)
			(stroke
				(width 0.1)
				(type default)
			)
			(layer "B.Fab")
		)
		(fp_line
			(start 0.12065 0.3048)
			(end 0.67945 0.3048)
			(stroke
				(width 0.1)
				(type default)
			)
			(layer "B.Fab")
		)
		(fp_line
			(start 0.67945 0.3048)
			(end 0.67945 -0.305054)
			(stroke
				(width 0.1)
				(type default)
			)
			(layer "B.Fab")
		)
		(fp_line
			(start -0.120396 0.2794)
			(end 0.12065 0.2794)
			(stroke
				(width 0.1)
				(type default)
			)
			(layer "B.Fab")
		)
		(fp_line
			(start 0.12065 0.2794)
			(end 0.12065 0.3048)
			(stroke
				(width 0.1)
				(type default)
			)
			(layer "B.Fab")
		)
		(fp_line
			(start -0.12065 -0.2794)
			(end -0.12065 -0.3048)
			(stroke
				(width 0.1)
				(type default)
			)
			(layer "B.Fab")
		)
		(fp_line
			(start 0.12065 -0.2794)
			(end -0.12065 -0.2794)
			(stroke
				(width 0.1)
				(type default)
			)
			(layer "B.Fab")
		)
		(fp_line
			(start -0.67945 -0.3048)
			(end -0.67945 0.3048)
			(stroke
				(width 0.1)
				(type default)
			)
			(layer "B.Fab")
		)
		(fp_line
			(start -0.12065 -0.3048)
			(end -0.67945 -0.3048)
			(stroke
				(width 0.1)
				(type default)
			)
			(layer "B.Fab")
		)
		(fp_line
			(start 0.12065 -0.305054)
			(end 0.12065 -0.2794)
			(stroke
				(width 0.1)
				(type default)
			)
			(layer "B.Fab")
		)
		(fp_line
			(start 0.67945 -0.305054)
			(end 0.12065 -0.305054)
			(stroke
				(width 0.1)
				(type default)
			)
			(layer "B.Fab")
		)
		(pad "1" smd circle
			(at 0.40005 0 90)
			(size 0 0)
			(layers "B.Cu" "B.Mask" "B.Paste")
			(net "P3V3_AUX")
		)
		(pad "2" smd circle
			(at -0.40005 0 90)
			(size 0 0)
			(layers "B.Cu" "B.Mask" "B.Paste")
			(net "BOARD_ID_1")
		)
	)
	(footprint ""
		(layer "B.Cu")
		(at 231.775 -82.296 -90)
		(property "Reference" "C5"
			(at 0 0 90)
			(layer "B.SilkS")
			(hide yes)
			(effects
				(font
					(size 1.27 1.27)
				)
				(justify mirror)
			)
		)
		(property "Value" ""
			(at 0 0 90)
			(layer "B.Fab")
			(effects
				(font
					(size 1.27 1.27)
				)
				(justify mirror)
			)
		)
		(duplicate_pad_numbers_are_jumpers no)
		(fp_line
			(start -0.7874 0.4064)
			(end 0.7874 0.4064)
			(stroke
				(width 0.1524)
				(type default)
			)
			(layer "B.SilkS")
		)
		(fp_line
			(start 0.7874 0.4064)
			(end 0.7874 -0.4064)
			(stroke
				(width 0.1524)
				(type default)
			)
			(layer "B.SilkS")
		)
		(fp_line
			(start -0.7874 -0.4064)
			(end -0.7874 0.4064)
			(stroke
				(width 0.1524)
				(type default)
			)
			(layer "B.SilkS")
		)
		(fp_line
			(start 0.7874 -0.4064)
			(end -0.7874 -0.4064)
			(stroke
				(width 0.1524)
				(type default)
			)
			(layer "B.SilkS")
		)
		(fp_line
			(start -0.67945 0.3048)
			(end -0.120396 0.3048)
			(stroke
				(width 0.1)
				(type default)
			)
			(layer "B.Fab")
		)
		(fp_line
			(start -0.120396 0.3048)
			(end -0.120396 0.2794)
			(stroke
				(width 0.1)
				(type default)
			)
			(layer "B.Fab")
		)
		(fp_line
			(start 0.12065 0.3048)
			(end 0.67945 0.3048)
			(stroke
				(width 0.1)
				(type default)
			)
			(layer "B.Fab")
		)
		(fp_line
			(start 0.67945 0.3048)
			(end 0.67945 -0.305054)
			(stroke
				(width 0.1)
				(type default)
			)
			(layer "B.Fab")
		)
		(fp_line
			(start -0.120396 0.2794)
			(end 0.12065 0.2794)
			(stroke
				(width 0.1)
				(type default)
			)
			(layer "B.Fab")
		)
		(fp_line
			(start 0.12065 0.2794)
			(end 0.12065 0.3048)
			(stroke
				(width 0.1)
				(type default)
			)
			(layer "B.Fab")
		)
		(fp_line
			(start -0.12065 -0.2794)
			(end -0.12065 -0.3048)
			(stroke
				(width 0.1)
				(type default)
			)
			(layer "B.Fab")
		)
		(fp_line
			(start 0.12065 -0.2794)
			(end -0.12065 -0.2794)
			(stroke
				(width 0.1)
				(type default)
			)
			(layer "B.Fab")
		)
		(fp_line
			(start -0.67945 -0.3048)
			(end -0.67945 0.3048)
			(stroke
				(width 0.1)
				(type default)
			)
			(layer "B.Fab")
		)
		(fp_line
			(start -0.12065 -0.3048)
			(end -0.67945 -0.3048)
			(stroke
				(width 0.1)
				(type default)
			)
			(layer "B.Fab")
		)
		(fp_line
			(start 0.12065 -0.305054)
			(end 0.12065 -0.2794)
			(stroke
				(width 0.1)
				(type default)
			)
			(layer "B.Fab")
		)
		(fp_line
			(start 0.67945 -0.305054)
			(end 0.12065 -0.305054)
			(stroke
				(width 0.1)
				(type default)
			)
			(layer "B.Fab")
		)
		(pad "1" smd circle
			(at 0.40005 0 90)
			(size 0 0)
			(layers "B.Cu" "B.Mask" "B.Paste")
			(net "P3V3_AUX")
		)
		(pad "2" smd circle
			(at -0.40005 0 90)
			(size 0 0)
			(layers "B.Cu" "B.Mask" "B.Paste")
			(net "GND")
		)
	)
	(footprint ""
		(layer "B.Cu")
		(at 210.058 -90.551 90)
		(property "Reference" "R29"
			(at 0 0 90)
			(layer "B.SilkS")
			(hide yes)
			(effects
				(font
					(size 1.27 1.27)
				)
				(justify mirror)
			)
		)
		(property "Value" ""
			(at 0 0 90)
			(layer "B.Fab")
			(effects
				(font
					(size 1.27 1.27)
				)
				(justify mirror)
			)
		)
		(duplicate_pad_numbers_are_jumpers no)
		(fp_line
			(start 0.7874 -0.4064)
			(end -0.7874 -0.4064)
			(stroke
				(width 0.1524)
				(type default)
			)
			(layer "B.SilkS")
		)
		(fp_line
			(start -0.7874 -0.4064)
			(end -0.7874 0.4064)
			(stroke
				(width 0.1524)
				(type default)
			)
			(layer "B.SilkS")
		)
		(fp_line
			(start 0.7874 0.4064)
			(end 0.7874 -0.4064)
			(stroke
				(width 0.1524)
				(type default)
			)
			(layer "B.SilkS")
		)
		(fp_line
			(start -0.7874 0.4064)
			(end 0.7874 0.4064)
			(stroke
				(width 0.1524)
				(type default)
			)
			(layer "B.SilkS")
		)
		(fp_line
			(start 0.67945 -0.305054)
			(end 0.12065 -0.305054)
			(stroke
				(width 0.1)
				(type default)
			)
			(layer "B.Fab")
		)
		(fp_line
			(start 0.12065 -0.305054)
			(end 0.12065 -0.2794)
			(stroke
				(width 0.1)
				(type default)
			)
			(layer "B.Fab")
		)
		(fp_line
			(start -0.12065 -0.3048)
			(end -0.67945 -0.3048)
			(stroke
				(width 0.1)
				(type default)
			)
			(layer "B.Fab")
		)
		(fp_line
			(start -0.67945 -0.3048)
			(end -0.67945 0.3048)
			(stroke
				(width 0.1)
				(type default)
			)
			(layer "B.Fab")
		)
		(fp_line
			(start 0.12065 -0.2794)
			(end -0.12065 -0.2794)
			(stroke
				(width 0.1)
				(type default)
			)
			(layer "B.Fab")
		)
		(fp_line
			(start -0.12065 -0.2794)
			(end -0.12065 -0.3048)
			(stroke
				(width 0.1)
				(type default)
			)
			(layer "B.Fab")
		)
		(fp_line
			(start 0.12065 0.2794)
			(end 0.12065 0.3048)
			(stroke
				(width 0.1)
				(type default)
			)
			(layer "B.Fab")
		)
		(fp_line
			(start -0.120396 0.2794)
			(end 0.12065 0.2794)
			(stroke
				(width 0.1)
				(type default)
			)
			(layer "B.Fab")
		)
		(fp_line
			(start 0.67945 0.3048)
			(end 0.67945 -0.305054)
			(stroke
				(width 0.1)
				(type default)
			)
			(layer "B.Fab")
		)
		(fp_line
			(start 0.12065 0.3048)
			(end 0.67945 0.3048)
			(stroke
				(width 0.1)
				(type default)
			)
			(layer "B.Fab")
		)
		(fp_line
			(start -0.120396 0.3048)
			(end -0.120396 0.2794)
			(stroke
				(width 0.1)
				(type default)
			)
			(layer "B.Fab")
		)
		(fp_line
			(start -0.67945 0.3048)
			(end -0.120396 0.3048)
			(stroke
				(width 0.1)
				(type default)
			)
			(layer "B.Fab")
		)
		(pad "1" smd circle
			(at 0.40005 0 270)
			(size 0 0)
			(layers "B.Cu" "B.Mask" "B.Paste")
			(net "P3V3_AUX")
		)
		(pad "2" smd circle
			(at -0.40005 0 270)
			(size 0 0)
			(layers "B.Cu" "B.Mask" "B.Paste")
			(net "PWRGD_GPU_HSC_BUF")
		)
	)
	(footprint ""
		(layer "B.Cu")
		(at 139.573 -114.046 90)
		(property "Reference" "R399"
			(at 0 0 90)
			(layer "B.SilkS")
			(hide yes)
			(effects
				(font
					(size 1.27 1.27)
				)
				(justify mirror)
			)
		)
		(property "Value" ""
			(at 0 0 90)
			(layer "B.Fab")
			(effects
				(font
					(size 1.27 1.27)
				)
				(justify mirror)
			)
		)
		(duplicate_pad_numbers_are_jumpers no)
		(fp_line
			(start 0.7874 -0.4064)
			(end -0.7874 -0.4064)
			(stroke
				(width 0.1524)
				(type default)
			)
			(layer "B.SilkS")
		)
		(fp_line
			(start -0.7874 -0.4064)
			(end -0.7874 0.4064)
			(stroke
				(width 0.1524)
				(type default)
			)
			(layer "B.SilkS")
		)
		(fp_line
			(start 0.7874 0.4064)
			(end 0.7874 -0.4064)
			(stroke
				(width 0.1524)
				(type default)
			)
			(layer "B.SilkS")
		)
		(fp_line
			(start -0.7874 0.4064)
			(end 0.7874 0.4064)
			(stroke
				(width 0.1524)
				(type default)
			)
			(layer "B.SilkS")
		)
		(fp_line
			(start 0.67945 -0.305054)
			(end 0.12065 -0.305054)
			(stroke
				(width 0.1)
				(type default)
			)
			(layer "B.Fab")
		)
		(fp_line
			(start 0.12065 -0.305054)
			(end 0.12065 -0.2794)
			(stroke
				(width 0.1)
				(type default)
			)
			(layer "B.Fab")
		)
		(fp_line
			(start -0.12065 -0.3048)
			(end -0.67945 -0.3048)
			(stroke
				(width 0.1)
				(type default)
			)
			(layer "B.Fab")
		)
		(fp_line
			(start -0.67945 -0.3048)
			(end -0.67945 0.3048)
			(stroke
				(width 0.1)
				(type default)
			)
			(layer "B.Fab")
		)
		(fp_line
			(start 0.12065 -0.2794)
			(end -0.12065 -0.2794)
			(stroke
				(width 0.1)
				(type default)
			)
			(layer "B.Fab")
		)
		(fp_line
			(start -0.12065 -0.2794)
			(end -0.12065 -0.3048)
			(stroke
				(width 0.1)
				(type default)
			)
			(layer "B.Fab")
		)
		(fp_line
			(start 0.12065 0.2794)
			(end 0.12065 0.3048)
			(stroke
				(width 0.1)
				(type default)
			)
			(layer "B.Fab")
		)
		(fp_line
			(start -0.120396 0.2794)
			(end 0.12065 0.2794)
			(stroke
				(width 0.1)
				(type default)
			)
			(layer "B.Fab")
		)
		(fp_line
			(start 0.67945 0.3048)
			(end 0.67945 -0.305054)
			(stroke
				(width 0.1)
				(type default)
			)
			(layer "B.Fab")
		)
		(fp_line
			(start 0.12065 0.3048)
			(end 0.67945 0.3048)
			(stroke
				(width 0.1)
				(type default)
			)
			(layer "B.Fab")
		)
		(fp_line
			(start -0.120396 0.3048)
			(end -0.120396 0.2794)
			(stroke
				(width 0.1)
				(type default)
			)
			(layer "B.Fab")
		)
		(fp_line
			(start -0.67945 0.3048)
			(end -0.120396 0.3048)
			(stroke
				(width 0.1)
				(type default)
			)
			(layer "B.Fab")
		)
		(pad "1" smd circle
			(at 0.40005 0 270)
			(size 0 0)
			(layers "B.Cu" "B.Mask" "B.Paste")
			(net "BRICK_P12V0_EN_N")
		)
		(pad "2" smd circle
			(at -0.40005 0 270)
			(size 0 0)
			(layers "B.Cu" "B.Mask" "B.Paste")
			(net "GND")
		)
	)
	(footprint ""
		(layer "B.Cu")
		(at 108.081826 -116.205)
		(property "Reference" "R200"
			(at 0 0 0)
			(layer "B.SilkS")
			(hide yes)
			(effects
				(font
					(size 1.27 1.27)
				)
				(justify mirror)
			)
		)
		(property "Value" ""
			(at 0 0 0)
			(layer "B.Fab")
			(effects
				(font
					(size 1.27 1.27)
				)
				(justify mirror)
			)
		)
		(duplicate_pad_numbers_are_jumpers no)
		(fp_line
			(start -0.7874 -0.4064)
			(end -0.7874 0.4064)
			(stroke
				(width 0.1524)
				(type default)
			)
			(layer "B.SilkS")
		)
		(fp_line
			(start -0.7874 0.4064)
			(end 0.7874 0.4064)
			(stroke
				(width 0.1524)
				(type default)
			)
			(layer "B.SilkS")
		)
		(fp_line
			(start 0.7874 -0.4064)
			(end -0.7874 -0.4064)
			(stroke
				(width 0.1524)
				(type default)
			)
			(layer "B.SilkS")
		)
		(fp_line
			(start 0.7874 0.4064)
			(end 0.7874 -0.4064)
			(stroke
				(width 0.1524)
				(type default)
			)
			(layer "B.SilkS")
		)
		(fp_line
			(start -0.67945 -0.3048)
			(end -0.67945 0.3048)
			(stroke
				(width 0.1)
				(type default)
			)
			(layer "B.Fab")
		)
		(fp_line
			(start -0.67945 0.3048)
			(end -0.120396 0.3048)
			(stroke
				(width 0.1)
				(type default)
			)
			(layer "B.Fab")
		)
		(fp_line
			(start -0.12065 -0.3048)
			(end -0.67945 -0.3048)
			(stroke
				(width 0.1)
				(type default)
			)
			(layer "B.Fab")
		)
		(fp_line
			(start -0.12065 -0.2794)
			(end -0.12065 -0.3048)
			(stroke
				(width 0.1)
				(type default)
			)
			(layer "B.Fab")
		)
		(fp_line
			(start -0.120396 0.2794)
			(end 0.12065 0.2794)
			(stroke
				(width 0.1)
				(type default)
			)
			(layer "B.Fab")
		)
		(fp_line
			(start -0.120396 0.3048)
			(end -0.120396 0.2794)
			(stroke
				(width 0.1)
				(type default)
			)
			(layer "B.Fab")
		)
		(fp_line
			(start 0.12065 -0.305054)
			(end 0.12065 -0.2794)
			(stroke
				(width 0.1)
				(type default)
			)
			(layer "B.Fab")
		)
		(fp_line
			(start 0.12065 -0.2794)
			(end -0.12065 -0.2794)
			(stroke
				(width 0.1)
				(type default)
			)
			(layer "B.Fab")
		)
		(fp_line
			(start 0.12065 0.2794)
			(end 0.12065 0.3048)
			(stroke
				(width 0.1)
				(type default)
			)
			(layer "B.Fab")
		)
		(fp_line
			(start 0.12065 0.3048)
			(end 0.67945 0.3048)
			(stroke
				(width 0.1)
				(type default)
			)
			(layer "B.Fab")
		)
		(fp_line
			(start 0.67945 -0.305054)
			(end 0.12065 -0.305054)
			(stroke
				(width 0.1)
				(type default)
			)
			(layer "B.Fab")
		)
		(fp_line
			(start 0.67945 0.3048)
			(end 0.67945 -0.305054)
			(stroke
				(width 0.1)
				(type default)
			)
			(layer "B.Fab")
		)
		(pad "1" smd circle
			(at 0.40005 0 180)
			(size 0 0)
			(layers "B.Cu" "B.Mask" "B.Paste")
			(net "P12V_BRICK0_PWRGD")
		)
		(pad "2" smd circle
			(at -0.40005 0 180)
			(size 0 0)
			(layers "B.Cu" "B.Mask" "B.Paste")
			(net "BRICK_P12V_1_EN_N")
		)
	)
)
